(kicad_pcb
	(version 20221018)
	(generator pcbnew)
	(general
    (thickness 1.656)
  )
	(paper "A4")
	(title_block
    (title "SDI-MIPI Bridge")
    (date "2023-08-09")
    (rev "1.3.4")
    (company "Antmicro")
		(comment 9 "footprints 80-91 of 190")
	)
	(layers
    (0 "F.Cu" signal)
    (1 "In1.Cu" power)
    (2 "In2.Cu" power)
    (3 "In3.Cu" signal)
    (4 "In4.Cu" signal)
    (31 "B.Cu" signal)
    (32 "B.Adhes" user "B.Adhesive")
    (33 "F.Adhes" user "F.Adhesive")
    (34 "B.Paste" user)
    (35 "F.Paste" user)
    (36 "B.SilkS" user "B.Silkscreen")
    (37 "F.SilkS" user "F.Silkscreen")
    (38 "B.Mask" user)
    (39 "F.Mask" user)
    (40 "Dwgs.User" user "User.Drawings")
    (41 "Cmts.User" user "User.Comments")
    (42 "Eco1.User" user "User.Eco1")
    (43 "Eco2.User" user "User.Eco2")
    (44 "Edge.Cuts" user)
    (45 "Margin" user)
    (46 "B.CrtYd" user "B.Courtyard")
    (47 "F.CrtYd" user "F.Courtyard")
    (48 "B.Fab" user)
    (49 "F.Fab" user)
  )
	(footprint "sdi-mipi-bridge-footprints:SW_SPST_4.2x2.8" (layer "F.Cu")
    (at 156.9 134.3 180)
    (descr "KMR211G")
    (tags "SPST Button Switch")
    (property "Author" "Antmicro")
    (property "License" "Apache-2.0")
    (property "MPN" "KMR211NGLFS")
    (property "Manufacturer" "C&K")
    (property "Sheetfile" "sdi-mipi-bridge.kicad_sch")
    (property "Sheetname" "")
    (attr smd)
    (fp_text reference "SW1" (at -1 -2.8) (layer "F.SilkS")
        (effects (font (size 0.65 0.65) (thickness 0.15)) (justify right bottom))
    )
    (fp_text value "SW_SPST_KMR211NGLFS" (at -3 3) (layer "F.Fab") hide
        (effects (font (size 0.7 0.7) (thickness 0.15)) (justify right bottom))
    )
    (fp_text user "License: Apache-2.0" (at -3 6.75) (layer "F.Fab") hide
        (effects (font (size 0.7 0.7) (thickness 0.15)) (justify right bottom))
    )
    (fp_text user "Author: Antmicro" (at -3 5.5) (layer "F.Fab") hide
        (effects (font (size 0.7 0.7) (thickness 0.15)) (justify right bottom))
    )
    (fp_text user "${REFERENCE}" (at -3 4.25) (layer "F.Fab") hide
        (effects (font (size 0.7 0.7) (thickness 0.15)) (justify right bottom))
    )
    (fp_line (start -2.101 -1.601) (end -2.101 -1.48)
      (stroke (width 0.15) (type solid)) (layer "F.SilkS"))
    (fp_line (start -2.101 -1.601) (end 2.1 -1.601)
      (stroke (width 0.15) (type solid)) (layer "F.SilkS"))
    (fp_line (start -2.101 1.58) (end -2.101 1.459)
      (stroke (width 0.15) (type solid)) (layer "F.SilkS"))
    (fp_line (start -2.101 1.6) (end 2.1 1.6)
      (stroke (width 0.15) (type solid)) (layer "F.SilkS"))
    (fp_line (start 2.1 -1.601) (end 2.1 -1.48)
      (stroke (width 0.15) (type solid)) (layer "F.SilkS"))
    (fp_line (start 2.1 1.6) (end 2.1 1.499)
      (stroke (width 0.15) (type solid)) (layer "F.SilkS"))
    (fp_rect (start -2.751 -1.75) (end 2.748 1.749)
      (stroke (width 0.05) (type solid)) (fill none) (layer "F.CrtYd"))
    (fp_line (start -2.101 -1.601) (end -2.101 1.6)
      (stroke (width 0.15) (type solid)) (layer "F.Fab"))
    (fp_line (start -2.101 1.6) (end 2.1 1.6)
      (stroke (width 0.15) (type solid)) (layer "F.Fab"))
    (fp_line (start -0.25 -0.802) (end 0.248 -0.802)
      (stroke (width 0.15) (type solid)) (layer "F.Fab"))
    (fp_line (start 0.248 0.8) (end -0.25 0.8)
      (stroke (width 0.15) (type solid)) (layer "F.Fab"))
    (fp_line (start 2.1 -1.601) (end -2.101 -1.601)
      (stroke (width 0.15) (type solid)) (layer "F.Fab"))
    (fp_line (start 2.1 1.6) (end 2.1 -1.601)
      (stroke (width 0.15) (type solid)) (layer "F.Fab"))
    (fp_arc (start -0.25 0.8) (mid -1.051001 -0.001) (end -0.25 -0.802)
      (stroke (width 0.15) (type solid)) (layer "F.Fab"))
    (fp_arc (start 0.248 -0.802) (mid 1.050001 -0.001) (end 0.248 0.8)
      (stroke (width 0.15) (type solid)) (layer "F.Fab"))
    (pad "1" smd rect (at 2.048 -0.802 180) (size 0.9 1) (layers "F.Cu" "F.Paste" "F.Mask")
      (net 3 "GNDA") (pintype "passive"))
    (pad "2" smd rect (at 2.048 0.8 180) (size 0.9 1) (layers "F.Cu" "F.Paste" "F.Mask")
      (net 125 "Net-(R82-Pad2)") (pintype "passive"))
    (pad "3" smd rect (at -2.05 -0.802 180) (size 0.9 1) (layers "F.Cu" "F.Paste" "F.Mask")
      (net 3 "GNDA") (pintype "passive"))
    (pad "4" smd rect (at -2.05 0.8 180) (size 0.9 1) (layers "F.Cu" "F.Paste" "F.Mask")
      (net 125 "Net-(R82-Pad2)") (pintype "passive"))
  )
	(footprint "sdi-mipi-bridge-footprints:R_0402_1005Metric" (layer "F.Cu")
    (at 145.5 129.75 90)
    (descr "Resistor SMD 0402")
    (tags "resistor SMD 0402")
    (property "Author" "Antmicro")
    (property "DNP" "DNP")
    (property "License" "Apache-2.0")
    (property "MPN" "CR0402-FX-1002GLF")
    (property "Manufacturer" "Bourns")
    (property "Sheetfile" "sdi-mipi-bridge.kicad_sch")
    (property "Sheetname" "")
    (property "Tolerance" "1%")
    (property "Val" "10k")
    (property "ki_description" "10k resistor in 0402 package with 1% tolerance")
    (attr exclude_from_pos_files)
    (fp_text reference "R99" (at -0.865 7.78 90) (layer "F.SilkS")
        (effects (font (size 0.65 0.65) (thickness 0.15)) (justify left bottom))
    )
    (fp_text value "R_10k_0402" (at 0 1.4 90) (layer "F.Fab") hide
        (effects (font (size 0.7 0.7) (thickness 0.15)) (justify left bottom))
    )
    (fp_text user "${REFERENCE}" (at -0.95 3.168 90) (layer "F.Fab") hide
        (effects (font (size 0.7 0.7) (thickness 0.15)) (justify left bottom))
    )
    (fp_text user "License: Apache-2.0" (at -0.95 5.169 90) (layer "F.Fab") hide
        (effects (font (size 0.7 0.7) (thickness 0.15)) (justify left bottom))
    )
    (fp_text user "Author: Antmicro" (at -0.95 4.169 90) (layer "F.Fab") hide
        (effects (font (size 0.7 0.7) (thickness 0.15)) (justify left bottom))
    )
    (fp_rect (start -0.93 -0.47) (end 0.93 0.47)
      (stroke (width 0.05) (type solid)) (fill none) (layer "F.CrtYd"))
    (fp_rect (start -0.5 -0.25) (end 0.5 0.25)
      (stroke (width 0.15) (type solid)) (fill none) (layer "F.Fab"))
    (pad "1" smd roundrect (at -0.485 0 90) (size 0.59 0.64) (layers "F.Cu" "F.Paste" "F.Mask") (roundrect_rratio 0.25)
      (net 18 "/DVB_ASI") (pintype "passive"))
    (pad "2" smd roundrect (at 0.485 0 90) (size 0.59 0.64) (layers "F.Cu" "F.Paste" "F.Mask") (roundrect_rratio 0.25)
      (net 76 "IO_VDD") (pintype "passive"))
  )
	(footprint "sdi-mipi-bridge-footprints:R_0402_1005Metric" (layer "F.Cu")
    (at 151.75 131.765 90)
    (descr "Resistor SMD 0402")
    (tags "resistor SMD 0402")
    (property "Author" "Antmicro")
    (property "License" "Apache-2.0")
    (property "MPN" "CR0402-FX-1002GLF")
    (property "Manufacturer" "Bourns")
    (property "Sheetfile" "sdi-mipi-bridge.kicad_sch")
    (property "Sheetname" "")
    (property "Tolerance" "1%")
    (property "Val" "10k")
    (property "ki_description" "10k resistor in 0402 package with 1% tolerance")
    (attr smd)
    (fp_text reference "R111" (at -5.75 0.4 90) (layer "F.SilkS")
        (effects (font (size 0.65 0.65) (thickness 0.15)) (justify left bottom))
    )
    (fp_text value "R_10k_0402" (at 0 1.4 90) (layer "F.Fab") hide
        (effects (font (size 0.7 0.7) (thickness 0.15)) (justify left bottom))
    )
    (fp_text user "License: Apache-2.0" (at -0.95 5.169 90) (layer "F.Fab") hide
        (effects (font (size 0.7 0.7) (thickness 0.15)) (justify left bottom))
    )
    (fp_text user "Author: Antmicro" (at -0.95 4.169 90) (layer "F.Fab") hide
        (effects (font (size 0.7 0.7) (thickness 0.15)) (justify left bottom))
    )
    (fp_text user "${REFERENCE}" (at -0.95 3.168 90) (layer "F.Fab") hide
        (effects (font (size 0.7 0.7) (thickness 0.15)) (justify left bottom))
    )
    (fp_rect (start -0.93 -0.47) (end 0.93 0.47)
      (stroke (width 0.05) (type solid)) (fill none) (layer "F.CrtYd"))
    (fp_rect (start -0.5 -0.25) (end 0.5 0.25)
      (stroke (width 0.15) (type solid)) (fill none) (layer "F.Fab"))
    (pad "1" smd roundrect (at -0.485 0 90) (size 0.59 0.64) (layers "F.Cu" "F.Paste" "F.Mask") (roundrect_rratio 0.25)
      (net 3 "GNDA") (pintype "passive"))
    (pad "2" smd roundrect (at 0.485 0 90) (size 0.59 0.64) (layers "F.Cu" "F.Paste" "F.Mask") (roundrect_rratio 0.25)
      (net 44 "/JTAG_~{HOST}") (pintype "passive"))
  )
	(footprint "sdi-mipi-bridge-footprints:R_0402_1005Metric" (layer "F.Cu")
    (at 146.75 129.75 90)
    (descr "Resistor SMD 0402")
    (tags "resistor SMD 0402")
    (property "Author" "Antmicro")
    (property "DNP" "DNP")
    (property "License" "Apache-2.0")
    (property "MPN" "CR0402-FX-1002GLF")
    (property "Manufacturer" "Bourns")
    (property "Sheetfile" "sdi-mipi-bridge.kicad_sch")
    (property "Sheetname" "")
    (property "Tolerance" "1%")
    (property "Val" "10k")
    (property "ki_description" "10k resistor in 0402 package with 1% tolerance")
    (attr exclude_from_pos_files)
    (fp_text reference "R101" (at -0.865 7.74 90) (layer "F.SilkS")
        (effects (font (size 0.65 0.65) (thickness 0.15)) (justify left bottom))
    )
    (fp_text value "R_10k_0402" (at 0 1.4 90) (layer "F.Fab") hide
        (effects (font (size 0.7 0.7) (thickness 0.15)) (justify left bottom))
    )
    (fp_text user "Author: Antmicro" (at -0.95 4.169 90) (layer "F.Fab") hide
        (effects (font (size 0.7 0.7) (thickness 0.15)) (justify left bottom))
    )
    (fp_text user "${REFERENCE}" (at -0.95 3.168 90) (layer "F.Fab") hide
        (effects (font (size 0.7 0.7) (thickness 0.15)) (justify left bottom))
    )
    (fp_text user "License: Apache-2.0" (at -0.95 5.169 90) (layer "F.Fab") hide
        (effects (font (size 0.7 0.7) (thickness 0.15)) (justify left bottom))
    )
    (fp_rect (start -0.93 -0.47) (end 0.93 0.47)
      (stroke (width 0.05) (type solid)) (fill none) (layer "F.CrtYd"))
    (fp_rect (start -0.5 -0.25) (end 0.5 0.25)
      (stroke (width 0.15) (type solid)) (fill none) (layer "F.Fab"))
    (pad "1" smd roundrect (at -0.485 0 90) (size 0.59 0.64) (layers "F.Cu" "F.Paste" "F.Mask") (roundrect_rratio 0.25)
      (net 47 "/SW_EN") (pintype "passive"))
    (pad "2" smd roundrect (at 0.485 0 90) (size 0.59 0.64) (layers "F.Cu" "F.Paste" "F.Mask") (roundrect_rratio 0.25)
      (net 76 "IO_VDD") (pintype "passive"))
  )
	(footprint "sdi-mipi-bridge-footprints:R_0402_1005Metric" (layer "F.Cu")
    (at 150.5 129.765 90)
    (descr "Resistor SMD 0402")
    (tags "resistor SMD 0402")
    (property "Author" "Antmicro")
    (property "DNP" "DNP")
    (property "License" "Apache-2.0")
    (property "MPN" "CR0402-FX-1002GLF")
    (property "Manufacturer" "Bourns")
    (property "Sheetfile" "sdi-mipi-bridge.kicad_sch")
    (property "Sheetname" "")
    (property "Tolerance" "1%")
    (property "Val" "10k")
    (property "ki_description" "10k resistor in 0402 package with 1% tolerance")
    (attr exclude_from_pos_files)
    (fp_text reference "R108" (at -0.85 7.62 90) (layer "F.SilkS")
        (effects (font (size 0.65 0.65) (thickness 0.15)) (justify left bottom))
    )
    (fp_text value "R_10k_0402" (at 0 1.4 90) (layer "F.Fab") hide
        (effects (font (size 0.7 0.7) (thickness 0.15)) (justify left bottom))
    )
    (fp_text user "Author: Antmicro" (at -0.95 4.169 90) (layer "F.Fab") hide
        (effects (font (size 0.7 0.7) (thickness 0.15)) (justify left bottom))
    )
    (fp_text user "License: Apache-2.0" (at -0.95 5.169 90) (layer "F.Fab") hide
        (effects (font (size 0.7 0.7) (thickness 0.15)) (justify left bottom))
    )
    (fp_text user "${REFERENCE}" (at -0.95 3.168 90) (layer "F.Fab") hide
        (effects (font (size 0.7 0.7) (thickness 0.15)) (justify left bottom))
    )
    (fp_rect (start -0.93 -0.47) (end 0.93 0.47)
      (stroke (width 0.05) (type solid)) (fill none) (layer "F.CrtYd"))
    (fp_rect (start -0.5 -0.25) (end 0.5 0.25)
      (stroke (width 0.15) (type solid)) (fill none) (layer "F.Fab"))
    (pad "1" smd roundrect (at -0.485 0 90) (size 0.59 0.64) (layers "F.Cu" "F.Paste" "F.Mask") (roundrect_rratio 0.25)
      (net 54 "/STANDBY") (pintype "passive"))
    (pad "2" smd roundrect (at 0.485 0 90) (size 0.59 0.64) (layers "F.Cu" "F.Paste" "F.Mask") (roundrect_rratio 0.25)
      (net 76 "IO_VDD") (pintype "passive"))
  )
	(footprint "sdi-mipi-bridge-footprints:R_0402_1005Metric" (layer "F.Cu")
    (at 151.75 129.75 90)
    (descr "Resistor SMD 0402")
    (tags "resistor SMD 0402")
    (property "Author" "Antmicro")
    (property "DNP" "DNP")
    (property "License" "Apache-2.0")
    (property "MPN" "CR0402-FX-1002GLF")
    (property "Manufacturer" "Bourns")
    (property "Sheetfile" "sdi-mipi-bridge.kicad_sch")
    (property "Sheetname" "")
    (property "Tolerance" "1%")
    (property "Val" "10k")
    (property "ki_description" "10k resistor in 0402 package with 1% tolerance")
    (attr exclude_from_pos_files)
    (fp_text reference "R110" (at -0.865 7.58 90) (layer "F.SilkS")
        (effects (font (size 0.65 0.65) (thickness 0.15)) (justify left bottom))
    )
    (fp_text value "R_10k_0402" (at 0 1.4 90) (layer "F.Fab") hide
        (effects (font (size 0.7 0.7) (thickness 0.15)) (justify left bottom))
    )
    (fp_text user "Author: Antmicro" (at -0.95 4.169 90) (layer "F.Fab") hide
        (effects (font (size 0.7 0.7) (thickness 0.15)) (justify left bottom))
    )
    (fp_text user "License: Apache-2.0" (at -0.95 5.169 90) (layer "F.Fab") hide
        (effects (font (size 0.7 0.7) (thickness 0.15)) (justify left bottom))
    )
    (fp_text user "${REFERENCE}" (at -0.95 3.168 90) (layer "F.Fab") hide
        (effects (font (size 0.7 0.7) (thickness 0.15)) (justify left bottom))
    )
    (fp_rect (start -0.93 -0.47) (end 0.93 0.47)
      (stroke (width 0.05) (type solid)) (fill none) (layer "F.CrtYd"))
    (fp_rect (start -0.5 -0.25) (end 0.5 0.25)
      (stroke (width 0.15) (type solid)) (fill none) (layer "F.Fab"))
    (pad "1" smd roundrect (at -0.485 0 90) (size 0.59 0.64) (layers "F.Cu" "F.Paste" "F.Mask") (roundrect_rratio 0.25)
      (net 44 "/JTAG_~{HOST}") (pintype "passive"))
    (pad "2" smd roundrect (at 0.485 0 90) (size 0.59 0.64) (layers "F.Cu" "F.Paste" "F.Mask") (roundrect_rratio 0.25)
      (net 76 "IO_VDD") (pintype "passive"))
  )
	(footprint "sdi-mipi-bridge-footprints:Mount-hole-M2.5" (layer "F.Cu")
    (at 101.5 135)
    (attr through_hole board_only)
    (fp_text reference "REF**" (at 0 0.5) (layer "F.SilkS") hide
        (effects (font (size 0.65 0.65) (thickness 0.12)))
    )
    (fp_text value "Mount-hole-M2.5" (at 0 -0.5) (layer "F.Fab") hide
        (effects (font (size 1 1) (thickness 0.15)))
    )
    (pad "1" thru_hole circle (at 0 0) (size 4.4 4.4) (drill 2.5) (layers "*.Cu" "*.Mask")
      (net 3 "GNDA"))
  )
	(footprint "sdi-mipi-bridge-footprints:R_0402_1005Metric" (layer "F.Cu")
    (at 146.75 131.75 90)
    (descr "Resistor SMD 0402")
    (tags "resistor SMD 0402")
    (property "Author" "Antmicro")
    (property "License" "Apache-2.0")
    (property "MPN" "CR0402-FX-1002GLF")
    (property "Manufacturer" "Bourns")
    (property "Sheetfile" "sdi-mipi-bridge.kicad_sch")
    (property "Sheetname" "")
    (property "Tolerance" "1%")
    (property "Val" "10k")
    (property "ki_description" "10k resistor in 0402 package with 1% tolerance")
    (attr smd)
    (fp_text reference "R102" (at -5.75 0.4 90) (layer "F.SilkS")
        (effects (font (size 0.65 0.65) (thickness 0.15)) (justify left bottom))
    )
    (fp_text value "R_10k_0402" (at 0 1.4 90) (layer "F.Fab") hide
        (effects (font (size 0.7 0.7) (thickness 0.15)) (justify left bottom))
    )
    (fp_text user "Author: Antmicro" (at -0.95 4.169 90) (layer "F.Fab") hide
        (effects (font (size 0.7 0.7) (thickness 0.15)) (justify left bottom))
    )
    (fp_text user "License: Apache-2.0" (at -0.95 5.169 90) (layer "F.Fab") hide
        (effects (font (size 0.7 0.7) (thickness 0.15)) (justify left bottom))
    )
    (fp_text user "${REFERENCE}" (at -0.95 3.168 90) (layer "F.Fab") hide
        (effects (font (size 0.7 0.7) (thickness 0.15)) (justify left bottom))
    )
    (fp_rect (start -0.93 -0.47) (end 0.93 0.47)
      (stroke (width 0.05) (type solid)) (fill none) (layer "F.CrtYd"))
    (fp_rect (start -0.5 -0.25) (end 0.5 0.25)
      (stroke (width 0.15) (type solid)) (fill none) (layer "F.Fab"))
    (pad "1" smd roundrect (at -0.485 0 90) (size 0.59 0.64) (layers "F.Cu" "F.Paste" "F.Mask") (roundrect_rratio 0.25)
      (net 3 "GNDA") (pintype "passive"))
    (pad "2" smd roundrect (at 0.485 0 90) (size 0.59 0.64) (layers "F.Cu" "F.Paste" "F.Mask") (roundrect_rratio 0.25)
      (net 47 "/SW_EN") (pintype "passive"))
  )
	(footprint "" (layer "F.Cu")
    (at 164.5 135)
    (attr board_only)
    (fp_text reference "" (at 0 0) (layer "F.SilkS")
        (effects (font (size 0.65 0.65) (thickness 0.12)))
    )
    (fp_text value "" (at 0 0) (layer "F.SilkS")
        (effects (font (size 1.27 1.27) (thickness 0.15)))
    )
    (pad "1" thru_hole circle (at 0 0) (size 4.4 4.4) (drill 2.5) (layers "*.Cu" "*.Mask")
      (net 1 "GNDREF"))
  )
	(footprint "" (layer "F.Cu")
    (at 164.5 98)
    (attr board_only)
    (fp_text reference "" (at 0 0) (layer "F.SilkS")
        (effects (font (size 0.65 0.65) (thickness 0.12)))
    )
    (fp_text value "" (at 0 0) (layer "F.SilkS")
        (effects (font (size 1.27 1.27) (thickness 0.15)))
    )
    (pad "1" thru_hole circle (at 0 0) (size 4.4 4.4) (drill 2.5) (layers "*.Cu" "*.Mask")
      (net 1 "GNDREF"))
  )
	(footprint "sdi-mipi-bridge-footprints:R_0402_1005Metric" (layer "F.Cu")
    (at 149.25 131.75 90)
    (descr "Resistor SMD 0402")
    (tags "resistor SMD 0402")
    (property "Author" "Antmicro")
    (property "License" "Apache-2.0")
    (property "MPN" "CR0402-FX-1002GLF")
    (property "Manufacturer" "Bourns")
    (property "Sheetfile" "sdi-mipi-bridge.kicad_sch")
    (property "Sheetname" "")
    (property "Tolerance" "1%")
    (property "Val" "10k")
    (property "ki_description" "10k resistor in 0402 package with 1% tolerance")
    (attr smd)
    (fp_text reference "R107" (at -5.75 0.4 90) (layer "F.SilkS")
        (effects (font (size 0.65 0.65) (thickness 0.15)) (justify left bottom))
    )
    (fp_text value "R_10k_0402" (at 0 1.4 90) (layer "F.Fab") hide
        (effects (font (size 0.7 0.7) (thickness 0.15)) (justify left bottom))
    )
    (fp_text user "Author: Antmicro" (at -0.95 4.169 90) (layer "F.Fab") hide
        (effects (font (size 0.7 0.7) (thickness 0.15)) (justify left bottom))
    )
    (fp_text user "${REFERENCE}" (at -0.95 3.168 90) (layer "F.Fab") hide
        (effects (font (size 0.7 0.7) (thickness 0.15)) (justify left bottom))
    )
    (fp_text user "License: Apache-2.0" (at -0.95 5.169 90) (layer "F.Fab") hide
        (effects (font (size 0.7 0.7) (thickness 0.15)) (justify left bottom))
    )
    (fp_rect (start -0.93 -0.47) (end 0.93 0.47)
      (stroke (width 0.05) (type solid)) (fill none) (layer "F.CrtYd"))
    (fp_rect (start -0.5 -0.25) (end 0.5 0.25)
      (stroke (width 0.15) (type solid)) (fill none) (layer "F.Fab"))
    (pad "1" smd roundrect (at -0.485 0 90) (size 0.59 0.64) (layers "F.Cu" "F.Paste" "F.Mask") (roundrect_rratio 0.25)
      (net 3 "GNDA") (pintype "passive"))
    (pad "2" smd roundrect (at 0.485 0 90) (size 0.59 0.64) (layers "F.Cu" "F.Paste" "F.Mask") (roundrect_rratio 0.25)
      (net 24 "/~{RC_BYP}") (pintype "passive"))
  )
	(footprint "sdi-mipi-bridge-footprints:R_0402_1005Metric" (layer "F.Cu")
    (at 150.5 131.765 90)
    (descr "Resistor SMD 0402")
    (tags "resistor SMD 0402")
    (property "Author" "Antmicro")
    (property "License" "Apache-2.0")
    (property "MPN" "CR0402-FX-1002GLF")
    (property "Manufacturer" "Bourns")
    (property "Sheetfile" "sdi-mipi-bridge.kicad_sch")
    (property "Sheetname" "")
    (property "Tolerance" "1%")
    (property "Val" "10k")
    (property "ki_description" "10k resistor in 0402 package with 1% tolerance")
    (attr smd)
    (fp_text reference "R109" (at -5.75 0.4 90) (layer "F.SilkS")
        (effects (font (size 0.65 0.65) (thickness 0.15)) (justify left bottom))
    )
    (fp_text value "R_10k_0402" (at 0 1.4 90) (layer "F.Fab") hide
        (effects (font (size 0.7 0.7) (thickness 0.15)) (justify left bottom))
    )
    (fp_text user "License: Apache-2.0" (at -0.95 5.169 90) (layer "F.Fab") hide
        (effects (font (size 0.7 0.7) (thickness 0.15)) (justify left bottom))
    )
    (fp_text user "${REFERENCE}" (at -0.95 3.168 90) (layer "F.Fab") hide
        (effects (font (size 0.7 0.7) (thickness 0.15)) (justify left bottom))
    )
    (fp_text user "Author: Antmicro" (at -0.95 4.169 90) (layer "F.Fab") hide
        (effects (font (size 0.7 0.7) (thickness 0.15)) (justify left bottom))
    )
    (fp_rect (start -0.93 -0.47) (end 0.93 0.47)
      (stroke (width 0.05) (type solid)) (fill none) (layer "F.CrtYd"))
    (fp_rect (start -0.5 -0.25) (end 0.5 0.25)
      (stroke (width 0.15) (type solid)) (fill none) (layer "F.Fab"))
    (pad "1" smd roundrect (at -0.485 0 90) (size 0.59 0.64) (layers "F.Cu" "F.Paste" "F.Mask") (roundrect_rratio 0.25)
      (net 3 "GNDA") (pintype "passive"))
    (pad "2" smd roundrect (at 0.485 0 90) (size 0.59 0.64) (layers "F.Cu" "F.Paste" "F.Mask") (roundrect_rratio 0.25)
      (net 54 "/STANDBY") (pintype "passive"))
  )
)
